# S9S_MB_2U (Grand Teton) — schematic netlist excerpt (pin names and nets, part order shuffled) for the footprints in the layout excerpt that follows; sources: Cadence DE-HDL packaged netlist, KiCad conversion of 03242023_DA0F0TMBIJ0_F0T_Motherboard_J_brd_V01_OCP.brd

R495  Q_RES  100 1% CHIP  pkg 0402LF  page 181 : A = PCH_PCIEUP_RCOMPP ; B = PCH_PCIEUP_RCOMPN
R2508  Q_RES  10K 1% EMPTY  pkg 0402LF  page 184 : A = P3V3_AUX ; B = FM_M2_SSD0_E7_PEDET

(kicad_pcb
	(version 20260206)
	(generator "pcbnew")
	(generator_version "10.0")
	(general
		(thickness 1.6)
		(legacy_teardrops no)
	)
	(paper "A4")
	(title_block
		(title "03242023_DA0F0TMBIJ0_F0T_Motherboard_J_brd_V01_OCP.brd")
		(comment 1 "Grand Teton / footprints 5440-5441 of 6105")
	)
	(layers
		(0 "F.Cu" signal "TOP")
		(4 "In1.Cu" signal "GND")
		(6 "In2.Cu" signal "IN1")
		(8 "In3.Cu" signal "GND1")
		(10 "In4.Cu" signal "IN2")
		(12 "In5.Cu" signal "GND2")
		(14 "In6.Cu" signal "IN3")
		(16 "In7.Cu" signal "GND3")
		(18 "In8.Cu" signal "VCC")
		(20 "In9.Cu" signal "VCC1")
		(22 "In10.Cu" signal "GND4")
		(24 "In11.Cu" signal "IN4")
		(26 "In12.Cu" signal "GND5")
		(28 "In13.Cu" signal "IN5")
		(30 "In14.Cu" signal "GND6")
		(32 "In15.Cu" signal "IN6")
		(34 "In16.Cu" signal "GND7")
		(2 "B.Cu" signal "BOTTOM")
		(9 "F.Adhes" user "F.Adhesive")
		(11 "B.Adhes" user "B.Adhesive")
		(13 "F.Paste" user "Package Geometry/Pastemask Top")
		(15 "B.Paste" user "Package Geometry/Pastemask Bottom")
		(5 "F.SilkS" user "Ref Des/Silkscreen Top")
		(7 "B.SilkS" user "Ref Des/Silkscreen Bottom")
		(1 "F.Mask" user "Board Geometry/Soldermask Top")
		(3 "B.Mask" user "Board Geometry/Soldermask Bottom")
		(17 "Dwgs.User" user "User.Drawings")
		(19 "Cmts.User" user "User.Comments")
		(21 "Eco1.User" user "User.Eco1")
		(23 "Eco2.User" user "User.Eco2")
		(25 "Edge.Cuts" user "Board Geometry/Outline")
		(27 "Margin" user)
		(31 "F.CrtYd" user "Package Geometry/Place Bound Top")
		(29 "B.CrtYd" user "Package Geometry/Place Bound Bottom")
		(35 "F.Fab" user "Ref Des/Assembly Top")
		(33 "B.Fab" user "Ref Des/Assembly Bottom")
	)
	(footprint ""
		(layer "B.Cu")
		(at 340.879938 -44.364402 -149.993)
		(property "Reference" "R495"
			(at 0 0 30.007)
			(layer "B.SilkS")
			(hide yes)
			(effects
				(font
					(size 1.27 1.27)
				)
				(justify mirror)
			)
		)
		(property "Value" ""
			(at 0 0 30.007)
			(layer "B.Fab")
			(effects
				(font
					(size 1.27 1.27)
				)
				(justify mirror)
			)
		)
		(duplicate_pad_numbers_are_jumpers no)
		(fp_line
			(start 0.787502 0.406396)
			(end 0.787346 -0.406469)
			(stroke
				(width 0.1524)
				(type default)
			)
			(layer "B.SilkS")
		)
		(fp_line
			(start 0.787346 -0.406469)
			(end -0.787502 -0.406396)
			(stroke
				(width 0.1524)
				(type default)
			)
			(layer "B.SilkS")
		)
		(fp_line
			(start -0.787346 0.406469)
			(end 0.787502 0.406396)
			(stroke
				(width 0.1524)
				(type default)
			)
			(layer "B.SilkS")
		)
		(fp_line
			(start -0.787502 -0.406396)
			(end -0.787346 0.406469)
			(stroke
				(width 0.1524)
				(type default)
			)
			(layer "B.SilkS")
		)
		(fp_line
			(start 0.67959 0.304771)
			(end 0.679513 -0.305075)
			(stroke
				(width 0.1)
				(type default)
			)
			(layer "B.Fab")
		)
		(fp_line
			(start 0.679513 -0.305075)
			(end 0.120769 -0.30511)
			(stroke
				(width 0.1)
				(type default)
			)
			(layer "B.Fab")
		)
		(fp_line
			(start 0.120499 0.304828)
			(end 0.67959 0.304771)
			(stroke
				(width 0.1)
				(type default)
			)
			(layer "B.Fab")
		)
		(fp_line
			(start 0.120552 0.279341)
			(end 0.120499 0.304828)
			(stroke
				(width 0.1)
				(type default)
			)
			(layer "B.Fab")
		)
		(fp_line
			(start -0.120295 0.304798)
			(end -0.120368 0.27953)
			(stroke
				(width 0.1)
				(type default)
			)
			(layer "B.Fab")
		)
		(fp_line
			(start -0.120368 0.27953)
			(end 0.120552 0.279341)
			(stroke
				(width 0.1)
				(type default)
			)
			(layer "B.Fab")
		)
		(fp_line
			(start 0.120588 -0.279403)
			(end -0.120552 -0.279341)
			(stroke
				(width 0.1)
				(type default)
			)
			(layer "B.Fab")
		)
		(fp_line
			(start 0.120769 -0.30511)
			(end 0.120588 -0.279403)
			(stroke
				(width 0.1)
				(type default)
			)
			(layer "B.Fab")
		)
		(fp_line
			(start -0.120552 -0.279341)
			(end -0.120499 -0.304828)
			(stroke
				(width 0.1)
				(type default)
			)
			(layer "B.Fab")
		)
		(fp_line
			(start -0.120499 -0.304828)
			(end -0.67959 -0.304771)
			(stroke
				(width 0.1)
				(type default)
			)
			(layer "B.Fab")
		)
		(fp_line
			(start -0.679386 0.304855)
			(end -0.120295 0.304798)
			(stroke
				(width 0.1)
				(type default)
			)
			(layer "B.Fab")
		)
		(fp_line
			(start -0.67959 -0.304771)
			(end -0.679386 0.304855)
			(stroke
				(width 0.1)
				(type default)
			)
			(layer "B.Fab")
		)
		(pad "1" smd circle
			(at 0.40005 0 30.007)
			(size 0 0)
			(layers "B.Cu" "B.Mask" "B.Paste")
			(net "PCH_PCIEUP_RCOMPP")
		)
		(pad "2" smd circle
			(at -0.40005 0 30.007)
			(size 0 0)
			(layers "B.Cu" "B.Mask" "B.Paste")
			(net "PCH_PCIEUP_RCOMPN")
		)
	)
	(footprint ""
		(layer "B.Cu")
		(at 372.41988 -43.144948)
		(property "Reference" "R2508"
			(at 0 0 0)
			(layer "B.SilkS")
			(hide yes)
			(effects
				(font
					(size 1.27 1.27)
				)
				(justify mirror)
			)
		)
		(property "Value" ""
			(at 0 0 0)
			(layer "B.Fab")
			(effects
				(font
					(size 1.27 1.27)
				)
				(justify mirror)
			)
		)
		(duplicate_pad_numbers_are_jumpers no)
		(fp_line
			(start -0.7874 -0.4064)
			(end -0.7874 0.4064)
			(stroke
				(width 0.1524)
				(type default)
			)
			(layer "B.SilkS")
		)
		(fp_line
			(start -0.7874 0.4064)
			(end 0.7874 0.4064)
			(stroke
				(width 0.1524)
				(type default)
			)
			(layer "B.SilkS")
		)
		(fp_line
			(start 0.7874 -0.4064)
			(end -0.7874 -0.4064)
			(stroke
				(width 0.1524)
				(type default)
			)
			(layer "B.SilkS")
		)
		(fp_line
			(start 0.7874 0.4064)
			(end 0.7874 -0.4064)
			(stroke
				(width 0.1524)
				(type default)
			)
			(layer "B.SilkS")
		)
		(fp_line
			(start -0.67945 -0.3048)
			(end -0.67945 0.3048)
			(stroke
				(width 0.1)
				(type default)
			)
			(layer "B.Fab")
		)
		(fp_line
			(start -0.67945 0.3048)
			(end -0.120396 0.3048)
			(stroke
				(width 0.1)
				(type default)
			)
			(layer "B.Fab")
		)
		(fp_line
			(start -0.12065 -0.3048)
			(end -0.67945 -0.3048)
			(stroke
				(width 0.1)
				(type default)
			)
			(layer "B.Fab")
		)
		(fp_line
			(start -0.12065 -0.2794)
			(end -0.12065 -0.3048)
			(stroke
				(width 0.1)
				(type default)
			)
			(layer "B.Fab")
		)
		(fp_line
			(start -0.120396 0.2794)
			(end 0.12065 0.2794)
			(stroke
				(width 0.1)
				(type default)
			)
			(layer "B.Fab")
		)
		(fp_line
			(start -0.120396 0.3048)
			(end -0.120396 0.2794)
			(stroke
				(width 0.1)
				(type default)
			)
			(layer "B.Fab")
		)
		(fp_line
			(start 0.12065 -0.305054)
			(end 0.12065 -0.2794)
			(stroke
				(width 0.1)
				(type default)
			)
			(layer "B.Fab")
		)
		(fp_line
			(start 0.12065 -0.2794)
			(end -0.12065 -0.2794)
			(stroke
				(width 0.1)
				(type default)
			)
			(layer "B.Fab")
		)
		(fp_line
			(start 0.12065 0.2794)
			(end 0.12065 0.3048)
			(stroke
				(width 0.1)
				(type default)
			)
			(layer "B.Fab")
		)
		(fp_line
			(start 0.12065 0.3048)
			(end 0.67945 0.3048)
			(stroke
				(width 0.1)
				(type default)
			)
			(layer "B.Fab")
		)
		(fp_line
			(start 0.67945 -0.305054)
			(end 0.12065 -0.305054)
			(stroke
				(width 0.1)
				(type default)
			)
			(layer "B.Fab")
		)
		(fp_line
			(start 0.67945 0.3048)
			(end 0.67945 -0.305054)
			(stroke
				(width 0.1)
				(type default)
			)
			(layer "B.Fab")
		)
		(pad "1" smd circle
			(at 0.40005 0 180)
			(size 0 0)
			(layers "B.Cu" "B.Mask" "B.Paste")
			(net "P3V3_AUX")
		)
		(pad "2" smd circle
			(at -0.40005 0 180)
			(size 0 0)
			(layers "B.Cu" "B.Mask" "B.Paste")
			(net "FM_M2_SSD0_E7_PEDET")
		)
	)
)
